# S9S_MB_2U (Grand Teton) — schematic netlist excerpt (pin names and nets, part order shuffled) for the footprints in the layout excerpt that follows; sources: Cadence DE-HDL packaged netlist, KiCad conversion of 03242023_DA0F0TMBIJ0_F0T_Motherboard_J_brd_V01_OCP.brd

R3185  Q_RES  33.2 1% CHIP  pkg 0402LF  page 161 : A = OCP_V3_2_WAKE_BUFF_N ; B = OCP_V3_2_WAKE_BUFF_R_N
R3859  Q_RES  0 5% EMPTY  pkg 0402LF  page 250 : A = P12V_OCP_V3_2_ISENSE_MAM_MAM ; B = P12V_OCP_V3_2_ISENSE_MAM

(kicad_pcb
	(version 20260206)
	(generator "pcbnew")
	(generator_version "10.0")
	(general
		(thickness 1.6)
		(legacy_teardrops no)
	)
	(paper "A4")
	(title_block
		(title "03242023_DA0F0TMBIJ0_F0T_Motherboard_J_brd_V01_OCP.brd")
		(comment 1 "Grand Teton / footprints 767-768 of 6105")
	)
	(layers
		(0 "F.Cu" signal "TOP")
		(4 "In1.Cu" signal "GND")
		(6 "In2.Cu" signal "IN1")
		(8 "In3.Cu" signal "GND1")
		(10 "In4.Cu" signal "IN2")
		(12 "In5.Cu" signal "GND2")
		(14 "In6.Cu" signal "IN3")
		(16 "In7.Cu" signal "GND3")
		(18 "In8.Cu" signal "VCC")
		(20 "In9.Cu" signal "VCC1")
		(22 "In10.Cu" signal "GND4")
		(24 "In11.Cu" signal "IN4")
		(26 "In12.Cu" signal "GND5")
		(28 "In13.Cu" signal "IN5")
		(30 "In14.Cu" signal "GND6")
		(32 "In15.Cu" signal "IN6")
		(34 "In16.Cu" signal "GND7")
		(2 "B.Cu" signal "BOTTOM")
		(9 "F.Adhes" user "F.Adhesive")
		(11 "B.Adhes" user "B.Adhesive")
		(13 "F.Paste" user "Package Geometry/Pastemask Top")
		(15 "B.Paste" user "Package Geometry/Pastemask Bottom")
		(5 "F.SilkS" user "Ref Des/Silkscreen Top")
		(7 "B.SilkS" user "Ref Des/Silkscreen Bottom")
		(1 "F.Mask" user "Board Geometry/Soldermask Top")
		(3 "B.Mask" user "Board Geometry/Soldermask Bottom")
		(17 "Dwgs.User" user "User.Drawings")
		(19 "Cmts.User" user "User.Comments")
		(21 "Eco1.User" user "User.Eco1")
		(23 "Eco2.User" user "User.Eco2")
		(25 "Edge.Cuts" user "Board Geometry/Outline")
		(27 "Margin" user)
		(31 "F.CrtYd" user "Package Geometry/Place Bound Top")
		(29 "B.CrtYd" user "Package Geometry/Place Bound Bottom")
		(35 "F.Fab" user "Ref Des/Assembly Top")
		(33 "B.Fab" user "Ref Des/Assembly Bottom")
	)
	(footprint ""
		(layer "F.Cu")
		(at 28.532328 -98.570034)
		(property "Reference" "R3859"
			(at 0 0 0)
			(layer "F.SilkS")
			(hide yes)
			(effects
				(font
					(size 1.27 1.27)
				)
			)
		)
		(property "Value" ""
			(at 0 0 0)
			(layer "F.Fab")
			(effects
				(font
					(size 1.27 1.27)
				)
			)
		)
		(duplicate_pad_numbers_are_jumpers no)
		(fp_line
			(start -0.7874 -0.4064)
			(end 0.7874 -0.4064)
			(stroke
				(width 0.1524)
				(type default)
			)
			(layer "F.SilkS")
		)
		(fp_line
			(start -0.7874 0.4064)
			(end -0.7874 -0.4064)
			(stroke
				(width 0.1524)
				(type default)
			)
			(layer "F.SilkS")
		)
		(fp_line
			(start 0.7874 -0.4064)
			(end 0.7874 0.4064)
			(stroke
				(width 0.1524)
				(type default)
			)
			(layer "F.SilkS")
		)
		(fp_line
			(start 0.7874 0.4064)
			(end -0.7874 0.4064)
			(stroke
				(width 0.1524)
				(type default)
			)
			(layer "F.SilkS")
		)
		(fp_line
			(start -0.67945 -0.305054)
			(end -0.12065 -0.305054)
			(stroke
				(width 0.1)
				(type default)
			)
			(layer "F.Fab")
		)
		(fp_line
			(start -0.67945 0.3048)
			(end -0.67945 -0.305054)
			(stroke
				(width 0.1)
				(type default)
			)
			(layer "F.Fab")
		)
		(fp_line
			(start -0.12065 -0.305054)
			(end -0.12065 -0.2794)
			(stroke
				(width 0.1)
				(type default)
			)
			(layer "F.Fab")
		)
		(fp_line
			(start -0.12065 -0.2794)
			(end 0.12065 -0.2794)
			(stroke
				(width 0.1)
				(type default)
			)
			(layer "F.Fab")
		)
		(fp_line
			(start -0.12065 0.2794)
			(end -0.12065 0.3048)
			(stroke
				(width 0.1)
				(type default)
			)
			(layer "F.Fab")
		)
		(fp_line
			(start -0.12065 0.3048)
			(end -0.67945 0.3048)
			(stroke
				(width 0.1)
				(type default)
			)
			(layer "F.Fab")
		)
		(fp_line
			(start 0.120396 0.2794)
			(end -0.12065 0.2794)
			(stroke
				(width 0.1)
				(type default)
			)
			(layer "F.Fab")
		)
		(fp_line
			(start 0.120396 0.3048)
			(end 0.120396 0.2794)
			(stroke
				(width 0.1)
				(type default)
			)
			(layer "F.Fab")
		)
		(fp_line
			(start 0.12065 -0.3048)
			(end 0.67945 -0.3048)
			(stroke
				(width 0.1)
				(type default)
			)
			(layer "F.Fab")
		)
		(fp_line
			(start 0.12065 -0.2794)
			(end 0.12065 -0.3048)
			(stroke
				(width 0.1)
				(type default)
			)
			(layer "F.Fab")
		)
		(fp_line
			(start 0.67945 -0.3048)
			(end 0.67945 0.3048)
			(stroke
				(width 0.1)
				(type default)
			)
			(layer "F.Fab")
		)
		(fp_line
			(start 0.67945 0.3048)
			(end 0.120396 0.3048)
			(stroke
				(width 0.1)
				(type default)
			)
			(layer "F.Fab")
		)
		(pad "1" smd rect
			(at -0.40005 0 180)
			(size 0.4572 0.508)
			(layers "F.Cu" "F.Mask" "F.Paste")
			(net "P12V_OCP_V3_2_ISENSE_MAM_MAM")
		)
		(pad "2" smd rect
			(at 0.40005 0 180)
			(size 0.4572 0.508)
			(layers "F.Cu" "F.Mask" "F.Paste")
			(net "P12V_OCP_V3_2_ISENSE_MAM")
		)
	)
	(footprint ""
		(layer "F.Cu")
		(at 274.495006 -21.259292 180)
		(property "Reference" "R3185"
			(at 0 0 180)
			(layer "F.SilkS")
			(hide yes)
			(effects
				(font
					(size 1.27 1.27)
				)
			)
		)
		(property "Value" ""
			(at 0 0 180)
			(layer "F.Fab")
			(effects
				(font
					(size 1.27 1.27)
				)
			)
		)
		(duplicate_pad_numbers_are_jumpers no)
		(fp_line
			(start 0.7874 0.4064)
			(end -0.7874 0.4064)
			(stroke
				(width 0.1524)
				(type default)
			)
			(layer "F.SilkS")
		)
		(fp_line
			(start 0.7874 -0.4064)
			(end 0.7874 0.4064)
			(stroke
				(width 0.1524)
				(type default)
			)
			(layer "F.SilkS")
		)
		(fp_line
			(start -0.7874 0.4064)
			(end -0.7874 -0.4064)
			(stroke
				(width 0.1524)
				(type default)
			)
			(layer "F.SilkS")
		)
		(fp_line
			(start -0.7874 -0.4064)
			(end 0.7874 -0.4064)
			(stroke
				(width 0.1524)
				(type default)
			)
			(layer "F.SilkS")
		)
		(fp_line
			(start 0.67945 0.3048)
			(end 0.120396 0.3048)
			(stroke
				(width 0.1)
				(type default)
			)
			(layer "F.Fab")
		)
		(fp_line
			(start 0.67945 -0.3048)
			(end 0.67945 0.3048)
			(stroke
				(width 0.1)
				(type default)
			)
			(layer "F.Fab")
		)
		(fp_line
			(start 0.12065 -0.2794)
			(end 0.12065 -0.3048)
			(stroke
				(width 0.1)
				(type default)
			)
			(layer "F.Fab")
		)
		(fp_line
			(start 0.12065 -0.3048)
			(end 0.67945 -0.3048)
			(stroke
				(width 0.1)
				(type default)
			)
			(layer "F.Fab")
		)
		(fp_line
			(start 0.120396 0.3048)
			(end 0.120396 0.2794)
			(stroke
				(width 0.1)
				(type default)
			)
			(layer "F.Fab")
		)
		(fp_line
			(start 0.120396 0.2794)
			(end -0.12065 0.2794)
			(stroke
				(width 0.1)
				(type default)
			)
			(layer "F.Fab")
		)
		(fp_line
			(start -0.12065 0.3048)
			(end -0.67945 0.3048)
			(stroke
				(width 0.1)
				(type default)
			)
			(layer "F.Fab")
		)
		(fp_line
			(start -0.12065 0.2794)
			(end -0.12065 0.3048)
			(stroke
				(width 0.1)
				(type default)
			)
			(layer "F.Fab")
		)
		(fp_line
			(start -0.12065 -0.2794)
			(end 0.12065 -0.2794)
			(stroke
				(width 0.1)
				(type default)
			)
			(layer "F.Fab")
		)
		(fp_line
			(start -0.12065 -0.305054)
			(end -0.12065 -0.2794)
			(stroke
				(width 0.1)
				(type default)
			)
			(layer "F.Fab")
		)
		(fp_line
			(start -0.67945 0.3048)
			(end -0.67945 -0.305054)
			(stroke
				(width 0.1)
				(type default)
			)
			(layer "F.Fab")
		)
		(fp_line
			(start -0.67945 -0.305054)
			(end -0.12065 -0.305054)
			(stroke
				(width 0.1)
				(type default)
			)
			(layer "F.Fab")
		)
		(pad "1" smd circle
			(at -0.40005 0 180)
			(size 0 0)
			(layers "F.Cu" "F.Mask" "F.Paste")
			(net "OCP_V3_2_WAKE_BUFF_N")
		)
		(pad "2" smd circle
			(at 0.40005 0 180)
			(size 0 0)
			(layers "F.Cu" "F.Mask" "F.Paste")
			(net "OCP_V3_2_WAKE_BUFF_R_N")
		)
	)
)
